(kicad_pcb
	(version 20260206)
	(generator "pcbnew")
	(generator_version "10.0")
	(general
		(thickness 1.6)
		(legacy_teardrops no)
	)
	(paper "A4")
	(title_block
		(title "Wiwynn_Tioga_Pass_MB.brd")
		(comment 1 "Tioga Pass / footprint 1664 of 4770 (U7C1), pads 578-695 of 1310")
	)
	(layers
		(0 "F.Cu" signal "TOP")
		(4 "In1.Cu" signal "L2GND")
		(6 "In2.Cu" signal "L3")
		(8 "In3.Cu" signal "L4GND")
		(10 "In4.Cu" signal "L5")
		(12 "In5.Cu" signal "L6GND")
		(14 "In6.Cu" signal "L7VCC")
		(16 "In7.Cu" signal "L8VCC")
		(18 "In8.Cu" signal "L9GND")
		(20 "In9.Cu" signal "L10")
		(22 "In10.Cu" signal "L11GND")
		(24 "In11.Cu" signal "L12")
		(26 "In12.Cu" signal "L13GND")
		(2 "B.Cu" signal "BOTTOM")
		(9 "F.Adhes" user "F.Adhesive")
		(11 "B.Adhes" user "B.Adhesive")
		(13 "F.Paste" user "Package Geometry/Pastemask Top")
		(15 "B.Paste" user "Package Geometry/Pastemask Bottom")
		(5 "F.SilkS" user "Ref Des/Silkscreen Top")
		(7 "B.SilkS" user "Ref Des/Silkscreen Bottom")
		(1 "F.Mask" user "Board Geometry/Soldermask Top")
		(3 "B.Mask" user "Board Geometry/Soldermask Bottom")
		(17 "Dwgs.User" user "User.Drawings")
		(19 "Cmts.User" user "User.Comments")
		(21 "Eco1.User" user "User.Eco1")
		(23 "Eco2.User" user "User.Eco2")
		(25 "Edge.Cuts" user "Board Geometry/Outline")
		(27 "Margin" user)
		(31 "F.CrtYd" user "Package Geometry/Place Bound Top")
		(29 "B.CrtYd" user "Package Geometry/Place Bound Bottom")
		(35 "F.Fab" user "Ref Des/Assembly Top")
		(33 "B.Fab" user "Ref Des/Assembly Bottom")
	)
	(footprint ""
		(layer "F.Cu")
		(at 387.985 -109.855 90)
		(property "Reference" "U7C1"
			(at 17.75333 -13.335 0)
			(unlocked yes)
			(layer "F.SilkS")
			(effects
				(font
					(size 0.7874 0.5842)
					(thickness 0.1524)
				)
				(justify left)
			)
		)
		(property "Value" ""
			(at 0 0 90)
			(layer "F.Fab")
			(effects
				(font
					(size 1.27 1.27)
				)
			)
		)
		(duplicate_pad_numbers_are_jumpers no)
		(pad "BE66" smd circle
			(at 13.73632 6.19125)
			(size 0.381 0.381)
			(layers "F.Cu" "F.Mask" "F.Paste")
			(net "GND")
		)
		(pad "BE69" smd circle
			(at 15.064994 6.500114)
			(size 0.3048 0.3048)
			(layers "F.Cu" "F.Mask" "F.Paste")
			(net "TP_USB3_P05_RXP")
		)
		(pad "BE71" smd circle
			(at 15.895066 6.500114)
			(size 0.3048 0.3048)
			(layers "F.Cu" "F.Mask" "F.Paste")
			(net "TP_USB3_P05_RXN")
		)
		(pad "BF1" smd oval
			(at -16.310102 6.999986 180)
			(size 0.254 0.3302)
			(layers "F.Cu" "F.Mask" "F.Paste")
			(net "SMB_LAN_STBY_LVC3_SCL_R1")
		)
		(pad "BF3" smd circle
			(at -15.48003 6.999986 180)
			(size 0.3048 0.3048)
			(layers "F.Cu" "F.Mask" "F.Paste")
			(net "FM_BMC_NMI_N")
		)
		(pad "BF5" smd circle
			(at -14.649958 6.999986 180)
			(size 0.3048 0.3048)
			(layers "F.Cu" "F.Mask" "F.Paste")
			(net "GND")
		)
		(pad "BF9" smd circle
			(at -12.8778 6.68655)
			(size 0.381 0.381)
			(layers "F.Cu" "F.Mask" "F.Paste")
			(net "GND")
		)
		(pad "BF13" smd circle
			(at -11.16076 6.68655)
			(size 0.381 0.381)
			(layers "F.Cu" "F.Mask" "F.Paste")
			(net "GND")
		)
		(pad "BF17" smd circle
			(at -9.44372 6.68655)
			(size 0.381 0.381)
			(layers "F.Cu" "F.Mask" "F.Paste")
			(net "GND")
		)
		(pad "BF20" smd circle
			(at -7.72668 6.68655)
			(size 0.381 0.381)
			(layers "F.Cu" "F.Mask" "F.Paste")
			(net "GND")
		)
		(pad "BF24" smd circle
			(at -6.00964 6.68655)
			(size 0.381 0.381)
			(layers "F.Cu" "F.Mask" "F.Paste")
			(net "GND")
		)
		(pad "BF27" smd circle
			(at -4.2926 6.68655)
			(size 0.381 0.381)
			(layers "F.Cu" "F.Mask" "F.Paste")
			(net "GND")
		)
		(pad "BF31" smd circle
			(at -2.57556 6.68655)
			(size 0.381 0.381)
			(layers "F.Cu" "F.Mask" "F.Paste")
			(net "KR_P0_OCP_RX_C_DP")
		)
		(pad "BF35" smd circle
			(at -0.85852 6.68655)
			(size 0.381 0.381)
			(layers "F.Cu" "F.Mask" "F.Paste")
			(net "Net_453")
		)
		(pad "BF38" smd circle
			(at 0.85852 6.68655)
			(size 0.381 0.381)
			(layers "F.Cu" "F.Mask" "F.Paste")
			(net "GND")
		)
		(pad "BF42" smd circle
			(at 2.57556 6.68655)
			(size 0.381 0.381)
			(layers "F.Cu" "F.Mask" "F.Paste")
			(net "GND")
		)
		(pad "BF46" smd circle
			(at 4.2926 6.68655)
			(size 0.381 0.381)
			(layers "F.Cu" "F.Mask" "F.Paste")
			(net "P1V05_PCH_STBY")
		)
		(pad "BF50" smd circle
			(at 6.00964 6.68655)
			(size 0.381 0.381)
			(layers "F.Cu" "F.Mask" "F.Paste")
			(net "GND")
		)
		(pad "BF54" smd circle
			(at 7.72668 6.68655)
			(size 0.381 0.381)
			(layers "F.Cu" "F.Mask" "F.Paste")
			(net "GND")
		)
		(pad "BF58" smd circle
			(at 9.44372 6.68655)
			(size 0.381 0.381)
			(layers "F.Cu" "F.Mask" "F.Paste")
			(net "GND")
		)
		(pad "BF61" smd circle
			(at 11.16076 6.68655)
			(size 0.381 0.381)
			(layers "F.Cu" "F.Mask" "F.Paste")
			(net "GND")
		)
		(pad "BF65" smd circle
			(at 12.8778 6.68655)
			(size 0.381 0.381)
			(layers "F.Cu" "F.Mask" "F.Paste")
			(net "GND")
		)
		(pad "BF68" smd circle
			(at 14.649958 6.999986)
			(size 0.3048 0.3048)
			(layers "F.Cu" "F.Mask" "F.Paste")
			(net "GND")
		)
		(pad "BF70" smd circle
			(at 15.48003 6.999986)
			(size 0.3048 0.3048)
			(layers "F.Cu" "F.Mask" "F.Paste")
			(net "TP_USB3_P04_RXP")
		)
		(pad "BF72" smd oval
			(at 16.310102 6.999986 180)
			(size 0.254 0.3302)
			(layers "F.Cu" "F.Mask" "F.Paste")
			(net "TP_USB3_P04_RXN")
		)
		(pad "BG7" smd circle
			(at -13.73632 7.18185)
			(size 0.381 0.381)
			(layers "F.Cu" "F.Mask" "F.Paste")
			(net "FM_SOL_UART_CH_SEL")
		)
		(pad "BG11" smd circle
			(at -12.01928 7.18185)
			(size 0.381 0.381)
			(layers "F.Cu" "F.Mask" "F.Paste")
			(net "Net_466")
		)
		(pad "BG15" smd circle
			(at -10.30224 7.18185)
			(size 0.381 0.381)
			(layers "F.Cu" "F.Mask" "F.Paste")
			(net "FM_PCH_PWRBTN_OUT_N")
		)
		(pad "BG18" smd circle
			(at -8.5852 7.18185)
			(size 0.381 0.381)
			(layers "F.Cu" "F.Mask" "F.Paste")
			(net "IRQ_PVDDQ_GHJ_VRHOT_LVT3_N")
		)
		(pad "BG22" smd circle
			(at -6.86816 7.18185)
			(size 0.381 0.381)
			(layers "F.Cu" "F.Mask" "F.Paste")
			(net "IRQ_PCH_NIC_ALERT_N")
		)
		(pad "BG26" smd circle
			(at -5.15112 7.18185)
			(size 0.381 0.381)
			(layers "F.Cu" "F.Mask" "F.Paste")
			(net "TP_PCH_RSVD27")
		)
		(pad "BG29" smd circle
			(at -3.43408 7.18185)
			(size 0.381 0.381)
			(layers "F.Cu" "F.Mask" "F.Paste")
			(net "KR_P1_OCP_RX_C_DN")
		)
		(pad "BG33" smd circle
			(at -1.71704 7.18185)
			(size 0.381 0.381)
			(layers "F.Cu" "F.Mask" "F.Paste")
			(net "GND")
		)
		(pad "BG37" smd circle
			(at 0 7.18185)
			(size 0.381 0.381)
			(layers "F.Cu" "F.Mask" "F.Paste")
			(net "Net_452")
		)
		(pad "BG40" smd circle
			(at 1.71704 7.18185)
			(size 0.381 0.381)
			(layers "F.Cu" "F.Mask" "F.Paste")
			(net "TP_PCH_RSVD42")
		)
		(pad "BG44" smd circle
			(at 3.43408 7.18185)
			(size 0.381 0.381)
			(layers "F.Cu" "F.Mask" "F.Paste")
			(net "GND")
		)
		(pad "BG48" smd circle
			(at 5.15112 7.18185)
			(size 0.381 0.381)
			(layers "F.Cu" "F.Mask" "F.Paste")
			(net "GND")
		)
		(pad "BG52" smd circle
			(at 6.86816 7.18185)
			(size 0.381 0.381)
			(layers "F.Cu" "F.Mask" "F.Paste")
			(net "FM_POST_CARD_PRES_BMC_R1_N")
		)
		(pad "BG56" smd circle
			(at 8.5852 7.18185)
			(size 0.381 0.381)
			(layers "F.Cu" "F.Mask" "F.Paste")
			(net "TP_USB3_P04_TXP")
		)
		(pad "BG59" smd circle
			(at 10.30224 7.18185)
			(size 0.381 0.381)
			(layers "F.Cu" "F.Mask" "F.Paste")
			(net "GND")
		)
		(pad "BG63" smd circle
			(at 12.01928 7.18185)
			(size 0.381 0.381)
			(layers "F.Cu" "F.Mask" "F.Paste")
			(net "GND")
		)
		(pad "BG66" smd circle
			(at 13.73632 7.18185)
			(size 0.381 0.381)
			(layers "F.Cu" "F.Mask" "F.Paste")
			(net "P2E_SSB_BMC_TX_DN")
		)
		(pad "BH2" smd circle
			(at -15.895066 7.500112 180)
			(size 0.3048 0.3048)
			(layers "F.Cu" "F.Mask" "F.Paste")
			(net "FM_PCH_BMC_THERMTRIP_N")
		)
		(pad "BH4" smd circle
			(at -15.064994 7.500112 180)
			(size 0.3048 0.3048)
			(layers "F.Cu" "F.Mask" "F.Paste")
			(net "FM_SSATA_PCIE_M2_SEL")
		)
		(pad "BH9" smd circle
			(at -12.8778 7.67715)
			(size 0.381 0.381)
			(layers "F.Cu" "F.Mask" "F.Paste")
			(net "VID_PCH_CORE_PVNN_AUX_VID_1")
		)
		(pad "BH13" smd circle
			(at -11.16076 7.67715)
			(size 0.381 0.381)
			(layers "F.Cu" "F.Mask" "F.Paste")
			(net "FM_BIOS_TOP_SWAP_SPKR")
		)
		(pad "BH17" smd circle
			(at -9.44372 7.67715)
			(size 0.381 0.381)
			(layers "F.Cu" "F.Mask" "F.Paste")
			(net "FM_FAST_PROCHOT_EN_N")
		)
		(pad "BH20" smd circle
			(at -7.72668 7.67715)
			(size 0.381 0.381)
			(layers "F.Cu" "F.Mask" "F.Paste")
			(net "FM_PWR_BTN_N")
		)
		(pad "BH24" smd circle
			(at -6.00964 7.67715)
			(size 0.381 0.381)
			(layers "F.Cu" "F.Mask" "F.Paste")
			(net "TP_PCH_RSVD26")
		)
		(pad "BH27" smd circle
			(at -4.2926 7.67715)
			(size 0.381 0.381)
			(layers "F.Cu" "F.Mask" "F.Paste")
			(net "GND")
		)
		(pad "BH31" smd circle
			(at -2.57556 7.67715)
			(size 0.381 0.381)
			(layers "F.Cu" "F.Mask" "F.Paste")
			(net "KR_P0_OCP_RX_C_DN")
		)
		(pad "BH35" smd circle
			(at -0.85852 7.67715)
			(size 0.381 0.381)
			(layers "F.Cu" "F.Mask" "F.Paste")
			(net "Net_454")
		)
		(pad "BH38" smd circle
			(at 0.85852 7.67715)
			(size 0.381 0.381)
			(layers "F.Cu" "F.Mask" "F.Paste")
			(net "GND")
		)
		(pad "BH42" smd circle
			(at 2.57556 7.67715)
			(size 0.381 0.381)
			(layers "F.Cu" "F.Mask" "F.Paste")
			(net "GND")
		)
		(pad "BH46" smd circle
			(at 4.2926 7.67715)
			(size 0.381 0.381)
			(layers "F.Cu" "F.Mask" "F.Paste")
			(net "GND")
		)
		(pad "BH50" smd circle
			(at 6.00964 7.67715)
			(size 0.381 0.381)
			(layers "F.Cu" "F.Mask" "F.Paste")
			(net "FM_CPU0_RC_ERROR_R1_N")
		)
		(pad "BH54" smd circle
			(at 7.72668 7.67715)
			(size 0.381 0.381)
			(layers "F.Cu" "F.Mask" "F.Paste")
			(net "GND")
		)
		(pad "BH58" smd circle
			(at 9.44372 7.67715)
			(size 0.381 0.381)
			(layers "F.Cu" "F.Mask" "F.Paste")
			(net "TP_USB3_P04_TXN")
		)
		(pad "BH61" smd circle
			(at 11.16076 7.67715)
			(size 0.381 0.381)
			(layers "F.Cu" "F.Mask" "F.Paste")
			(net "P3E_PCH_M2_TX_DN<3>")
		)
		(pad "BH65" smd circle
			(at 12.8778 7.67715)
			(size 0.381 0.381)
			(layers "F.Cu" "F.Mask" "F.Paste")
			(net "PE_PCH_SPRV_TX_DN")
		)
		(pad "BH69" smd circle
			(at 15.064994 7.500112)
			(size 0.3048 0.3048)
			(layers "F.Cu" "F.Mask" "F.Paste")
			(net "TP_USB3_P03_RXP")
		)
		(pad "BH71" smd circle
			(at 15.895066 7.500112)
			(size 0.3048 0.3048)
			(layers "F.Cu" "F.Mask" "F.Paste")
			(net "TP_USB3_P03_RXN")
		)
		(pad "BJ1" smd oval
			(at -16.310102 7.999984 180)
			(size 0.254 0.3302)
			(layers "F.Cu" "F.Mask" "F.Paste")
			(net "GND")
		)
		(pad "BJ3" smd circle
			(at -15.48003 7.999984 180)
			(size 0.3048 0.3048)
			(layers "F.Cu" "F.Mask" "F.Paste")
			(net "GND")
		)
		(pad "BJ5" smd circle
			(at -14.649958 7.999984 180)
			(size 0.3048 0.3048)
			(layers "F.Cu" "F.Mask" "F.Paste")
			(net "GND")
		)
		(pad "BJ7" smd circle
			(at -13.73632 8.17245)
			(size 0.381 0.381)
			(layers "F.Cu" "F.Mask" "F.Paste")
			(net "GND")
		)
		(pad "BJ11" smd circle
			(at -12.01928 8.17245)
			(size 0.381 0.381)
			(layers "F.Cu" "F.Mask" "F.Paste")
			(net "GND")
		)
		(pad "BJ15" smd circle
			(at -10.30224 8.17245)
			(size 0.381 0.381)
			(layers "F.Cu" "F.Mask" "F.Paste")
			(net "GND")
		)
		(pad "BJ18" smd circle
			(at -8.5852 8.17245)
			(size 0.381 0.381)
			(layers "F.Cu" "F.Mask" "F.Paste")
			(net "GND")
		)
		(pad "BJ22" smd circle
			(at -6.86816 8.17245)
			(size 0.381 0.381)
			(layers "F.Cu" "F.Mask" "F.Paste")
			(net "FM_BIOS_POST_CMPLT_N")
		)
		(pad "BJ26" smd circle
			(at -5.15112 8.17245)
			(size 0.381 0.381)
			(layers "F.Cu" "F.Mask" "F.Paste")
			(net "GND")
		)
		(pad "BJ29" smd circle
			(at -3.43408 8.17245)
			(size 0.381 0.381)
			(layers "F.Cu" "F.Mask" "F.Paste")
			(net "KR_P1_OCP_RX_C_DP")
		)
		(pad "BJ33" smd circle
			(at -1.71704 8.17245)
			(size 0.381 0.381)
			(layers "F.Cu" "F.Mask" "F.Paste")
			(net "GND")
		)
		(pad "BJ37" smd circle
			(at 0 8.17245)
			(size 0.381 0.381)
			(layers "F.Cu" "F.Mask" "F.Paste")
			(net "Net_451")
		)
		(pad "BJ40" smd circle
			(at 1.71704 8.17245)
			(size 0.381 0.381)
			(layers "F.Cu" "F.Mask" "F.Paste")
			(net "TP_PCH_RSVD41")
		)
		(pad "BJ44" smd circle
			(at 3.43408 8.17245)
			(size 0.381 0.381)
			(layers "F.Cu" "F.Mask" "F.Paste")
			(net "IRQ_HSC_FAULT_N")
		)
		(pad "BJ48" smd circle
			(at 5.15112 8.17245)
			(size 0.381 0.381)
			(layers "F.Cu" "F.Mask" "F.Paste")
			(net "FM_ADR_SMI_GPIO_N")
		)
		(pad "BJ52" smd circle
			(at 6.86816 8.17245)
			(size 0.381 0.381)
			(layers "F.Cu" "F.Mask" "F.Paste")
			(net "GND")
		)
		(pad "BJ56" smd circle
			(at 8.5852 8.17245)
			(size 0.381 0.381)
			(layers "F.Cu" "F.Mask" "F.Paste")
			(net "TP_USB3_P02_TXP")
		)
		(pad "BJ59" smd circle
			(at 10.30224 8.17245)
			(size 0.381 0.381)
			(layers "F.Cu" "F.Mask" "F.Paste")
			(net "TP_USB3_P05_TXP")
		)
		(pad "BJ63" smd circle
			(at 12.01928 8.17245)
			(size 0.381 0.381)
			(layers "F.Cu" "F.Mask" "F.Paste")
			(net "PE_PCH_SPRV_TX_DP")
		)
		(pad "BJ66" smd circle
			(at 13.73632 8.17245)
			(size 0.381 0.381)
			(layers "F.Cu" "F.Mask" "F.Paste")
			(net "P2E_SSB_BMC_TX_DP")
		)
		(pad "BJ68" smd circle
			(at 14.649958 7.999984)
			(size 0.3048 0.3048)
			(layers "F.Cu" "F.Mask" "F.Paste")
			(net "GND")
		)
		(pad "BJ70" smd circle
			(at 15.48003 7.999984)
			(size 0.3048 0.3048)
			(layers "F.Cu" "F.Mask" "F.Paste")
			(net "TP_USB3_P02_RXP")
		)
		(pad "BJ72" smd oval
			(at 16.310102 7.999984 180)
			(size 0.254 0.3302)
			(layers "F.Cu" "F.Mask" "F.Paste")
			(net "TP_USB3_P02_RXN")
		)
		(pad "BK2" smd circle
			(at -15.895066 8.50011 180)
			(size 0.3048 0.3048)
			(layers "F.Cu" "F.Mask" "F.Paste")
			(net "LED_GBE_P1_1")
		)
		(pad "BK4" smd circle
			(at -15.064994 8.50011 180)
			(size 0.3048 0.3048)
			(layers "F.Cu" "F.Mask" "F.Paste")
			(net "LED_GBE_P0_1")
		)
		(pad "BK9" smd circle
			(at -12.8778 8.66775)
			(size 0.381 0.381)
			(layers "F.Cu" "F.Mask" "F.Paste")
			(net "FM_PMBUS_ALERT_BUF_EN_R2_N")
		)
		(pad "BK13" smd circle
			(at -11.16076 8.66775)
			(size 0.381 0.381)
			(layers "F.Cu" "F.Mask" "F.Paste")
			(net "FM_UART_ALERT_N")
		)
		(pad "BK17" smd circle
			(at -9.44372 8.66775)
			(size 0.381 0.381)
			(layers "F.Cu" "F.Mask" "F.Paste")
			(net "IRQ_PVDDQ_DEF_VRHOT_LVT3_N")
		)
		(pad "BK20" smd circle
			(at -7.72668 8.66775)
			(size 0.381 0.381)
			(layers "F.Cu" "F.Mask" "F.Paste")
			(net "FM_BIOS_PREFRB2_GOOD")
		)
		(pad "BK24" smd circle
			(at -6.00964 8.66775)
			(size 0.381 0.381)
			(layers "F.Cu" "F.Mask" "F.Paste")
			(net "GND")
		)
		(pad "BK27" smd circle
			(at -4.2926 8.66775)
			(size 0.381 0.381)
			(layers "F.Cu" "F.Mask" "F.Paste")
			(net "GND")
		)
		(pad "BK31" smd circle
			(at -2.57556 8.66775)
			(size 0.381 0.381)
			(layers "F.Cu" "F.Mask" "F.Paste")
			(net "GND")
		)
		(pad "BK35" smd circle
			(at -0.85852 8.66775)
			(size 0.381 0.381)
			(layers "F.Cu" "F.Mask" "F.Paste")
			(net "GND")
		)
		(pad "BK38" smd circle
			(at 0.85852 8.66775)
			(size 0.381 0.381)
			(layers "F.Cu" "F.Mask" "F.Paste")
			(net "GND")
		)
		(pad "BK42" smd circle
			(at 2.57556 8.66775)
			(size 0.381 0.381)
			(layers "F.Cu" "F.Mask" "F.Paste")
			(net "GND")
		)
		(pad "BK46" smd circle
			(at 4.2926 8.66775)
			(size 0.381 0.381)
			(layers "F.Cu" "F.Mask" "F.Paste")
			(net "FM_PWR_LED_N")
		)
		(pad "BK50" smd circle
			(at 6.00964 8.66775)
			(size 0.381 0.381)
			(layers "F.Cu" "F.Mask" "F.Paste")
			(net "GND")
		)
		(pad "BK54" smd circle
			(at 7.72668 8.66775)
			(size 0.381 0.381)
			(layers "F.Cu" "F.Mask" "F.Paste")
			(net "USB3_P01_TXP")
		)
		(pad "BK58" smd circle
			(at 9.44372 8.66775)
			(size 0.381 0.381)
			(layers "F.Cu" "F.Mask" "F.Paste")
			(net "TP_USB3_P05_TXN")
		)
		(pad "BK61" smd circle
			(at 11.16076 8.66775)
			(size 0.381 0.381)
			(layers "F.Cu" "F.Mask" "F.Paste")
			(net "P3E_PCH_M2_TX_DP<3>")
		)
		(pad "BK65" smd circle
			(at 12.8778 8.66775)
			(size 0.381 0.381)
			(layers "F.Cu" "F.Mask" "F.Paste")
			(net "P3E_PCH_M2_TX_DN<2>")
		)
		(pad "BK69" smd circle
			(at 15.064994 8.50011)
			(size 0.3048 0.3048)
			(layers "F.Cu" "F.Mask" "F.Paste")
			(net "USB3_P01_RXP")
		)
		(pad "BK71" smd circle
			(at 15.895066 8.50011)
			(size 0.3048 0.3048)
			(layers "F.Cu" "F.Mask" "F.Paste")
			(net "USB3_P01_RXN")
		)
		(pad "BL1" smd oval
			(at -16.310102 8.999982 180)
			(size 0.254 0.3302)
			(layers "F.Cu" "F.Mask" "F.Paste")
			(net "LED_GBE_P0_0")
		)
		(pad "BL3" smd circle
			(at -15.48003 8.999982 180)
			(size 0.3048 0.3048)
			(layers "F.Cu" "F.Mask" "F.Paste")
			(net "LED_GBE_P2_0")
		)
		(pad "BL5" smd circle
			(at -14.649958 8.999982 180)
			(size 0.3048 0.3048)
			(layers "F.Cu" "F.Mask" "F.Paste")
			(net "GND")
		)
		(pad "BL7" smd circle
			(at -13.73632 9.16305)
			(size 0.381 0.381)
			(layers "F.Cu" "F.Mask" "F.Paste")
			(net "VID_PCH_CORE_PVNN_AUX_VID_0")
		)
		(pad "BL11" smd circle
			(at -12.01928 9.16305)
			(size 0.381 0.381)
			(layers "F.Cu" "F.Mask" "F.Paste")
			(net "RST_SYSTEM_BTN_N")
		)
		(pad "BL15" smd circle
			(at -10.30224 9.16305)
			(size 0.381 0.381)
			(layers "F.Cu" "F.Mask" "F.Paste")
			(net "FM_UV_ADR_TRIGGER_EN")
		)
		(pad "BL18" smd circle
			(at -8.5852 9.16305)
			(size 0.381 0.381)
			(layers "F.Cu" "F.Mask" "F.Paste")
			(net "FM_GLOBAL_RST_WARN_N")
		)
		(pad "BL22" smd circle
			(at -6.86816 9.16305)
			(size 0.381 0.381)
			(layers "F.Cu" "F.Mask" "F.Paste")
			(net "GND")
		)
		(pad "BL26" smd circle
			(at -5.15112 9.16305)
			(size 0.381 0.381)
			(layers "F.Cu" "F.Mask" "F.Paste")
			(net "TP_10GBE_KR0_MON_DN")
		)
		(pad "BL29" smd circle
			(at -3.43408 9.16305)
			(size 0.381 0.381)
			(layers "F.Cu" "F.Mask" "F.Paste")
			(net "TP_PCH_RSVD38")
		)
		(pad "BL33" smd circle
			(at -1.71704 9.16305)
			(size 0.381 0.381)
			(layers "F.Cu" "F.Mask" "F.Paste")
			(net "TP_10GBE_KR1_MON_DN")
		)
		(pad "BL37" smd circle
			(at 0 9.16305)
			(size 0.381 0.381)
			(layers "F.Cu" "F.Mask" "F.Paste")
			(net "GND")
		)
		(pad "BL40" smd circle
			(at 1.71704 9.16305)
			(size 0.381 0.381)
			(layers "F.Cu" "F.Mask" "F.Paste")
			(net "GND")
		)
	)
)
